(kicad_pcb
	(version 20241229)
	(generator "pcbnew")
	(generator_version "9.0")
	(general
		(thickness 1.599998)
		(legacy_teardrops no)
	)
	(paper "A4")
	(title_block
		(title "Artix - Datacenter Secure Control Module (DC-SCM)")
		(date "2024-11-06")
		(rev "1.1.3")
		(comment 9 "footprints 107-109 of 544")
	)
	(layers
		(0 "F.Cu" signal)
		(4 "In1.Cu" signal)
		(6 "In2.Cu" signal)
		(8 "In3.Cu" signal)
		(10 "In4.Cu" signal)
		(12 "In5.Cu" signal)
		(14 "In6.Cu" signal)
		(2 "B.Cu" signal)
		(9 "F.Adhes" user "F.Adhesive")
		(11 "B.Adhes" user "B.Adhesive")
		(13 "F.Paste" user)
		(15 "B.Paste" user)
		(5 "F.SilkS" user "F.Silkscreen")
		(7 "B.SilkS" user "B.Silkscreen")
		(1 "F.Mask" user)
		(3 "B.Mask" user)
		(17 "Dwgs.User" user "User.Drawings")
		(19 "Cmts.User" user "User.Comments")
		(21 "Eco1.User" user "User.Eco1")
		(23 "Eco2.User" user "User.Eco2")
		(25 "Edge.Cuts" user)
		(27 "Margin" user)
		(31 "F.CrtYd" user "F.Courtyard")
		(29 "B.CrtYd" user "B.Courtyard")
		(35 "F.Fab" user)
		(33 "B.Fab" user)
	)
	(footprint "antmicro-footprints:SOIC-8_5.3x5.3x2mm_P1.27mm"
		(layer "F.Cu")
		(at 66.45 147.405 90)
		(descr "8-Pin SOIC 208-mil")
		(property "Reference" "U5"
			(at -0.0015 -3.2 90)
			(layer "F.SilkS")
			(effects
				(font
					(size 0.7 0.7)
					(thickness 0.15)
				)
				(justify left bottom)
			)
		)
		(property "Value" "W25Q32JW_SOIC-8"
			(at 0 3.8 90)
			(layer "F.Fab")
			(effects
				(font
					(size 0.7 0.7)
					(thickness 0.15)
				)
				(justify left bottom)
			)
		)
		(property "Datasheet" "https://www.mouser.com/datasheet/2/949/w25q32jw_spi_revf_09042018-1489621.pdf"
			(at 0 0 90)
			(layer "F.Fab")
			(hide yes)
			(effects
				(font
					(size 1.27 1.27)
					(thickness 0.15)
				)
			)
		)
		(property "Description" "FLASH - NOR Memory IC 32Mbit SPI - Quad I/O 133 MHz 8-SOIC"
			(at 0 0 90)
			(layer "F.Fab")
			(hide yes)
			(effects
				(font
					(size 1.27 1.27)
					(thickness 0.15)
				)
			)
		)
		(property "Author" "Antmicro"
			(at 213.855 80.955 0)
			(layer "F.Fab")
			(hide yes)
			(effects
				(font
					(size 1 1)
					(thickness 0.15)
				)
			)
		)
		(property "License" "Apache-2.0"
			(at 213.855 80.955 0)
			(layer "F.Fab")
			(hide yes)
			(effects
				(font
					(size 1 1)
					(thickness 0.15)
				)
			)
		)
		(property "MPN" "W25Q32JWSSIQ"
			(at 213.855 80.955 0)
			(layer "F.Fab")
			(hide yes)
			(effects
				(font
					(size 1 1)
					(thickness 0.15)
				)
			)
		)
		(property "Manufacturer" "Winbond"
			(at 213.855 80.955 0)
			(layer "F.Fab")
			(hide yes)
			(effects
				(font
					(size 1 1)
					(thickness 0.15)
				)
			)
		)
		(sheetname "/RoT/")
		(sheetfile "rot.kicad_sch")
		(attr smd)
		(fp_line
			(start -2.8 -2.641)
			(end -4.4 -2.641)
			(stroke
				(width 0.15)
				(type solid)
			)
			(layer "F.SilkS")
		)
		(fp_circle
			(center -4.85 -1.905)
			(end -4.8 -1.855)
			(stroke
				(width 0.15)
				(type solid)
			)
			(fill yes)
			(layer "F.SilkS")
		)
		(fp_rect
			(start 4.675 -3)
			(end -4.675 3)
			(stroke
				(width 0.05)
				(type solid)
			)
			(fill no)
			(layer "F.CrtYd")
		)
		(fp_line
			(start 2.64 -2.641)
			(end 2.64 2.64)
			(stroke
				(width 0.15)
				(type solid)
			)
			(layer "F.Fab")
		)
		(fp_line
			(start -2.641 -2.641)
			(end 2.64 -2.641)
			(stroke
				(width 0.15)
				(type solid)
			)
			(layer "F.Fab")
		)
		(fp_line
			(start -2.641 -1.371)
			(end -1.371 -2.641)
			(stroke
				(width 0.15)
				(type solid)
			)
			(layer "F.Fab")
		)
		(fp_line
			(start 2.64 2.64)
			(end -2.641 2.64)
			(stroke
				(width 0.15)
				(type solid)
			)
			(layer "F.Fab")
		)
		(fp_line
			(start -2.641 2.64)
			(end -2.641 -2.641)
			(stroke
				(width 0.15)
				(type solid)
			)
			(layer "F.Fab")
		)
		(pad "1" smd roundrect
			(at -3.601 -1.905 180)
			(size 0.65 1.65)
			(layers "F.Cu" "F.Mask" "F.Paste")
			(roundrect_rratio 0.25)
			(net 135 "QSPIA1_CS_N")
			(pinfunction "~{CS}")
			(pintype "input")
		)
		(pad "2" smd roundrect
			(at -3.601 -0.635 180)
			(size 0.65 1.65)
			(layers "F.Cu" "F.Mask" "F.Paste")
			(roundrect_rratio 0.25)
			(net 132 "QSPIA1_D1")
			(pinfunction "SO/IO1")
			(pintype "bidirectional")
		)
		(pad "3" smd roundrect
			(at -3.601 0.633 180)
			(size 0.65 1.65)
			(layers "F.Cu" "F.Mask" "F.Paste")
			(roundrect_rratio 0.25)
			(net 133 "QSPIA1_D2")
			(pinfunction "~{WP}/IO2")
			(pintype "bidirectional")
		)
		(pad "4" smd roundrect
			(at -3.601 1.904 180)
			(size 0.65 1.65)
			(layers "F.Cu" "F.Mask" "F.Paste")
			(roundrect_rratio 0.25)
			(net 1 "GND")
			(pinfunction "VSS")
			(pintype "power_in")
		)
		(pad "5" smd roundrect
			(at 3.6 1.904 180)
			(size 0.65 1.65)
			(layers "F.Cu" "F.Mask" "F.Paste")
			(roundrect_rratio 0.25)
			(net 131 "QSPIA1_D0")
			(pinfunction "SI/IO0")
			(pintype "bidirectional")
		)
		(pad "6" smd roundrect
			(at 3.6 0.633 180)
			(size 0.65 1.65)
			(layers "F.Cu" "F.Mask" "F.Paste")
			(roundrect_rratio 0.25)
			(net 130 "QSPIA_CLK")
			(pinfunction "SCLK")
			(pintype "input")
		)
		(pad "7" smd roundrect
			(at 3.6 -0.635 180)
			(size 0.65 1.65)
			(layers "F.Cu" "F.Mask" "F.Paste")
			(roundrect_rratio 0.25)
			(net 134 "QSPIA1_D3")
			(pinfunction "~{HOLD}/IO3")
			(pintype "bidirectional")
		)
		(pad "8" smd roundrect
			(at 3.6 -1.905 180)
			(size 0.65 1.65)
			(layers "F.Cu" "F.Mask" "F.Paste")
			(roundrect_rratio 0.25)
			(net 2 "VCC3V3")
			(pinfunction "VCC")
			(pintype "power_in")
		)
	)
	(footprint "antmicro-footprints:RJ45_BEL_L834-1G1T-S7"
		(layer "F.Cu")
		(at 99.595 80.835 180)
		(property "Reference" "J1"
			(at -13.505 -4.165 180)
			(layer "F.SilkS")
			(effects
				(font
					(size 0.7 0.7)
					(thickness 0.15)
				)
				(justify left bottom)
			)
		)
		(property "Value" "L834-1G1T-S7"
			(at -2.92 -5.906 180)
			(layer "F.Fab")
			(effects
				(font
					(size 0.7 0.7)
					(thickness 0.15)
				)
				(justify left bottom)
			)
		)
		(property "Datasheet" "https://www.belfuse.com/resources/drawings/magneticsolutions/dr-mag-l834-1g1t-s7.pdf"
			(at 0 0 180)
			(layer "F.Fab")
			(hide yes)
			(effects
				(font
					(size 1.27 1.27)
					(thickness 0.15)
				)
			)
		)
		(property "Description" "Modular connector with magnetics"
			(at 0 0 180)
			(layer "F.Fab")
			(hide yes)
			(effects
				(font
					(size 1.27 1.27)
					(thickness 0.15)
				)
			)
		)
		(property "Author" "Antmicro"
			(at 199.19 161.67 0)
			(layer "F.Fab")
			(hide yes)
			(effects
				(font
					(size 1 1)
					(thickness 0.15)
				)
			)
		)
		(property "License" "Apache-2.0"
			(at 199.19 161.67 0)
			(layer "F.Fab")
			(hide yes)
			(effects
				(font
					(size 1 1)
					(thickness 0.15)
				)
			)
		)
		(property "MPN" "L834-1G1T-S7"
			(at 199.19 161.67 0)
			(layer "F.Fab")
			(hide yes)
			(effects
				(font
					(size 1 1)
					(thickness 0.15)
				)
			)
		)
		(property "Manufacturer" "Bel Fuse"
			(at 199.19 161.67 0)
			(layer "F.Fab")
			(hide yes)
			(effects
				(font
					(size 1 1)
					(thickness 0.15)
				)
			)
		)
		(sheetname "/Ethernet/")
		(sheetfile "ethernet.kicad_sch")
		(attr through_hole)
		(fp_line
			(start 3.179 12.53)
			(end 3.179 18.158)
			(stroke
				(width 0.15)
				(type solid)
			)
			(layer "F.SilkS")
		)
		(fp_line
			(start 3.179 8.13)
			(end 3.179 9.529)
			(stroke
				(width 0.15)
				(type solid)
			)
			(layer "F.SilkS")
		)
		(fp_line
			(start 3.179 -4.121)
			(end 3.179 1.929)
			(stroke
				(width 0.15)
				(type solid)
			)
			(layer "F.SilkS")
		)
		(fp_line
			(start 3.179 -4.121)
			(end -13.34 -4.121)
			(stroke
				(width 0.15)
				(type solid)
			)
			(layer "F.SilkS")
		)
		(fp_line
			(start -13.34 10.13)
			(end -13.34 18.158)
			(stroke
				(width 0.15)
				(type solid)
			)
			(layer "F.SilkS")
		)
		(fp_line
			(start -13.34 2.53)
			(end -13.34 3.93)
			(stroke
				(width 0.15)
				(type solid)
			)
			(layer "F.SilkS")
		)
		(fp_line
			(start -13.34 -4.121)
			(end -13.34 -0.471)
			(stroke
				(width 0.15)
				(type solid)
			)
			(layer "F.SilkS")
		)
		(fp_line
			(start 4.87 22.19)
			(end -15.06 22.19)
			(stroke
				(width 0.05)
				(type solid)
			)
			(layer "F.CrtYd")
		)
		(fp_line
			(start 4.87 -0.3)
			(end 4.87 22.19)
			(stroke
				(width 0.05)
				(type solid)
			)
			(layer "F.CrtYd")
		)
		(fp_line
			(start 4.87 -0.3)
			(end 3.5 -0.3)
			(stroke
				(width 0.05)
				(type solid)
			)
			(layer "F.CrtYd")
		)
		(fp_line
			(start 3.5 -0.3)
			(end 3.5 -4.4)
			(stroke
				(width 0.05)
				(type solid)
			)
			(layer "F.CrtYd")
		)
		(fp_line
			(start -13.6 -0.3)
			(end -13.6 -4.4)
			(stroke
				(width 0.05)
				(type solid)
			)
			(layer "F.CrtYd")
		)
		(fp_line
			(start -13.6 -0.3)
			(end -15.06 -0.3)
			(stroke
				(width 0.05)
				(type solid)
			)
			(layer "F.CrtYd")
		)
		(fp_line
			(start -13.6 -4.4)
			(end 3.5 -4.4)
			(stroke
				(width 0.05)
				(type solid)
			)
			(layer "F.CrtYd")
		)
		(fp_line
			(start -15.06 22.19)
			(end -15.06 -0.3)
			(stroke
				(width 0.05)
				(type solid)
			)
			(layer "F.CrtYd")
		)
		(fp_line
			(start 3.179 21.94)
			(end 3.179 -4.121)
			(stroke
				(width 0.15)
				(type solid)
			)
			(layer "F.Fab")
		)
		(fp_line
			(start 3.179 -4.121)
			(end -13.34 -4.121)
			(stroke
				(width 0.15)
				(type solid)
			)
			(layer "F.Fab")
		)
		(fp_line
			(start -13.34 21.94)
			(end 3.179 21.94)
			(stroke
				(width 0.15)
				(type solid)
			)
			(layer "F.Fab")
		)
		(fp_line
			(start -13.34 -4.121)
			(end -13.34 21.94)
			(stroke
				(width 0.15)
				(type solid)
			)
			(layer "F.Fab")
		)
		(fp_arc
			(start 4.578 14.192)
			(mid 4.389 18.158)
			(end 3.179 21.94)
			(stroke
				(width 0.15)
				(type solid)
			)
			(layer "F.Fab")
		)
		(fp_arc
			(start -13.34 21.94)
			(mid -14.551 18.158)
			(end -14.74 14.192)
			(stroke
				(width 0.15)
				(type solid)
			)
			(layer "F.Fab")
		)
		(pad "" np_thru_hole circle
			(at -13.235 1.009 180)
			(size 2.31 2.31)
			(drill 2.31)
			(layers "*.Cu" "*.Mask")
		)
		(pad "" np_thru_hole circle
			(at -13.235 8.63 180)
			(size 2.31 2.31)
			(drill 2.31)
			(layers "*.Cu" "*.Mask")
		)
		(pad "" np_thru_hole circle
			(at 3.073 3.43 180)
			(size 2.31 2.31)
			(drill 2.31)
			(layers "*.Cu" "*.Mask")
		)
		(pad "" np_thru_hole circle
			(at 3.073 11.047 180)
			(size 2.31 2.31)
			(drill 2.31)
			(layers "*.Cu" "*.Mask")
		)
		(pad "1" thru_hole rect
			(at 0 0 180)
			(size 1.53 1.53)
			(drill 1.02)
			(layers "*.Cu" "*.Mask")
			(remove_unused_layers no)
			(net 204 "Net-(J1-TRCT3)")
			(pinfunction "TRCT3")
			(pintype "passive")
		)
		(pad "2" thru_hole circle
			(at -2.032 0 180)
			(size 1.53 1.53)
			(drill 1.02)
			(layers "*.Cu" "*.Mask")
			(remove_unused_layers no)
			(net 430 "/Ethernet/ETH3_N")
			(pinfunction "TRD3-")
			(pintype "passive")
		)
		(pad "3" thru_hole circle
			(at -4.064 0 180)
			(size 1.53 1.53)
			(drill 1.02)
			(layers "*.Cu" "*.Mask")
			(remove_unused_layers no)
			(net 431 "/Ethernet/ETH3_P")
			(pinfunction "TRD3+")
			(pintype "passive")
		)
		(pad "4" thru_hole circle
			(at -6.096 0 180)
			(size 1.53 1.53)
			(drill 1.02)
			(layers "*.Cu" "*.Mask")
			(remove_unused_layers no)
			(net 433 "/Ethernet/ETH2_P")
			(pinfunction "TRD2+")
			(pintype "passive")
		)
		(pad "5" thru_hole circle
			(at -8.128 0 180)
			(size 1.53 1.53)
			(drill 1.02)
			(layers "*.Cu" "*.Mask")
			(remove_unused_layers no)
			(net 432 "/Ethernet/ETH2_N")
			(pinfunction "TRD2-")
			(pintype "passive")
		)
		(pad "6" thru_hole circle
			(at -10.16 0 180)
			(size 1.53 1.53)
			(drill 1.02)
			(layers "*.Cu" "*.Mask")
			(remove_unused_layers no)
			(net 203 "Net-(J1-TRCT2)")
			(pinfunction "TRCT2")
			(pintype "passive")
		)
		(pad "7" thru_hole circle
			(at 1.015 -2.54 180)
			(size 1.53 1.53)
			(drill 1.02)
			(layers "*.Cu" "*.Mask")
			(remove_unused_layers no)
			(net 206 "Net-(J1-TRCT4)")
			(pinfunction "TRCT4")
			(pintype "passive")
		)
		(pad "8" thru_hole circle
			(at -1.016 -2.54 180)
			(size 1.53 1.53)
			(drill 1.02)
			(layers "*.Cu" "*.Mask")
			(remove_unused_layers no)
			(net 429 "/Ethernet/ETH4_P")
			(pinfunction "TRD4+")
			(pintype "passive")
		)
		(pad "9" thru_hole circle
			(at -3.048 -2.54 180)
			(size 1.53 1.53)
			(drill 1.02)
			(layers "*.Cu" "*.Mask")
			(remove_unused_layers no)
			(net 428 "/Ethernet/ETH4_N")
			(pinfunction "TRD4-")
			(pintype "passive")
		)
		(pad "10" thru_hole circle
			(at -7.112 -2.54 180)
			(size 1.53 1.53)
			(drill 1.02)
			(layers "*.Cu" "*.Mask")
			(remove_unused_layers no)
			(net 434 "/Ethernet/ETH1_N")
			(pinfunction "TRD1-")
			(pintype "passive")
		)
		(pad "11" thru_hole circle
			(at -9.144 -2.54 180)
			(size 1.53 1.53)
			(drill 1.02)
			(layers "*.Cu" "*.Mask")
			(remove_unused_layers no)
			(net 435 "/Ethernet/ETH1_P")
			(pinfunction "TRD1+")
			(pintype "passive")
		)
		(pad "12" thru_hole circle
			(at -11.176 -2.54 180)
			(size 1.53 1.53)
			(drill 1.02)
			(layers "*.Cu" "*.Mask")
			(remove_unused_layers no)
			(net 202 "Net-(J1-TRCT1)")
			(pinfunction "TRCT1")
			(pintype "passive")
		)
		(pad "13" thru_hole circle
			(at 1.945 13.97 180)
			(size 1.725 1.725)
			(drill 1.15)
			(layers "*.Cu" "*.Mask")
			(remove_unused_layers no)
			(net 575 "Net-(J1-Pad13)")
			(pintype "passive")
		)
		(pad "14" thru_hole circle
			(at 1.945 16.508 180)
			(size 1.725 1.725)
			(drill 1.15)
			(layers "*.Cu" "*.Mask")
			(remove_unused_layers no)
			(net 2 "VCC3V3")
			(pintype "passive")
		)
		(pad "15" thru_hole circle
			(at -12.106 13.97 180)
			(size 1.725 1.725)
			(drill 1.15)
			(layers "*.Cu" "*.Mask")
			(remove_unused_layers no)
			(net 574 "Net-(J1-Pad15)")
			(pintype "passive")
		)
		(pad "16" thru_hole circle
			(at -12.106 16.508 180)
			(size 1.725 1.725)
			(drill 1.15)
			(layers "*.Cu" "*.Mask")
			(remove_unused_layers no)
			(net 2 "VCC3V3")
			(pintype "passive")
		)
		(pad "SH" thru_hole circle
			(at -13.235 5.328 180)
			(size 2.1 2.1)
			(drill 1.4)
			(layers "*.Cu" "*.Mask")
			(remove_unused_layers no)
			(net 1 "GND")
			(pinfunction "SH")
			(pintype "passive")
		)
		(pad "SH" thru_hole circle
			(at 3.073 6.73 180)
			(size 2.1 2.1)
			(drill 1.4)
			(layers "*.Cu" "*.Mask")
			(remove_unused_layers no)
			(net 1 "GND")
			(pinfunction "SH")
			(pintype "passive")
		)
	)
	(footprint "antmicro-footprints:R_0402_1005Metric"
		(layer "F.Cu")
		(at 75.74 162.06 -90)
		(descr "Resistor SMD 0402")
		(tags "resistor SMD 0402")
		(property "Reference" "R48"
			(at -2.16 -8.36 90)
			(layer "F.SilkS")
			(effects
				(font
					(size 0.7 0.7)
					(thickness 0.15)
				)
				(justify right bottom)
			)
		)
		(property "Value" "R_357k_0402"
			(at 0 1.4 90)
			(layer "F.Fab")
			(effects
				(font
					(size 0.7 0.7)
					(thickness 0.15)
				)
				(justify right bottom)
			)
		)
		(property "Datasheet" "https://www.bourns.com/docs/product-datasheets/cr.pdf"
			(at 0 0 270)
			(layer "F.Fab")
			(hide yes)
			(effects
				(font
					(size 1.27 1.27)
					(thickness 0.15)
				)
			)
		)
		(property "Description" "SMD Chip Resistor"
			(at 0 0 270)
			(layer "F.Fab")
			(hide yes)
			(effects
				(font
					(size 1.27 1.27)
					(thickness 0.15)
				)
			)
		)
		(property "Author" "Antmicro"
			(at -86.32 237.8 0)
			(layer "F.Fab")
			(hide yes)
			(effects
				(font
					(size 1 1)
					(thickness 0.15)
				)
			)
		)
		(property "License" "Apache-2.0"
			(at -86.32 237.8 0)
			(layer "F.Fab")
			(hide yes)
			(effects
				(font
					(size 1 1)
					(thickness 0.15)
				)
			)
		)
		(property "MPN" "CR0402-FX-3573GLF"
			(at -86.32 237.8 0)
			(layer "F.Fab")
			(hide yes)
			(effects
				(font
					(size 1 1)
					(thickness 0.15)
				)
			)
		)
		(property "Manufacturer" "Bourns"
			(at -86.32 237.8 0)
			(layer "F.Fab")
			(hide yes)
			(effects
				(font
					(size 1 1)
					(thickness 0.15)
				)
			)
		)
		(property "Tolerance" "1%"
			(at -86.32 237.8 0)
			(layer "F.Fab")
			(hide yes)
			(effects
				(font
					(size 1 1)
					(thickness 0.15)
				)
			)
		)
		(property "Val" "357k"
			(at -86.32 237.8 0)
			(layer "F.Fab")
			(hide yes)
			(effects
				(font
					(size 1 1)
					(thickness 0.15)
				)
			)
		)
		(sheetname "/Interfaces/")
		(sheetfile "interfaces.kicad_sch")
		(attr smd)
		(fp_rect
			(start -0.925 -0.47)
			(end 0.925 0.47)
			(stroke
				(width 0.05)
				(type default)
			)
			(fill no)
			(layer "F.CrtYd")
		)
		(fp_rect
			(start -0.5 -0.25)
			(end 0.5 0.25)
			(stroke
				(width 0.15)
				(type solid)
			)
			(fill no)
			(layer "F.Fab")
		)
		(pad "1" smd roundrect
			(at -0.48 0 270)
			(size 0.59 0.64)
			(layers "F.Cu" "F.Mask" "F.Paste")
			(roundrect_rratio 0.25)
			(net 2 "VCC3V3")
			(pintype "passive")
		)
		(pad "2" smd roundrect
			(at 0.48 0 270)
			(size 0.59 0.64)
			(layers "F.Cu" "F.Mask" "F.Paste")
			(roundrect_rratio 0.25)
			(net 171 "I3C[1]_SCL_3V3")
			(pintype "passive")
		)
	)
)
